# S9S_MB_2U (Grand Teton) — schematic netlist excerpt (pin names and nets, part order shuffled) for the footprints in the layout excerpt that follows; sources: Cadence DE-HDL packaged netlist, KiCad conversion of 03242023_DA0F0TMBIJ0_F0T_Motherboard_J_brd_V01_OCP.brd

C461  Q_CAP  47UF 4V 20% X6S  pkg C0805  page 78 : A = PVCCFA_EHV_FIVRA_CPU1 ; B = GND
C330  Q_CAP  47UF 4V 20% X6S  pkg C0805  page 78 : A = PVCCIN_CPU1 ; B = GND
C526  Q_CAP  47UF 4V 20% X6S  pkg C0805  page 76 : A = PVCCFA_EHV_FIVRA_CPU0 ; B = GND

(kicad_pcb
	(version 20260206)
	(generator "pcbnew")
	(generator_version "10.0")
	(general
		(thickness 1.6)
		(legacy_teardrops no)
	)
	(paper "A4")
	(title_block
		(title "03242023_DA0F0TMBIJ0_F0T_Motherboard_J_brd_V01_OCP.brd")
		(comment 1 "Grand Teton / footprints 4681-4683 of 6105")
	)
	(layers
		(0 "F.Cu" signal "TOP")
		(4 "In1.Cu" signal "GND")
		(6 "In2.Cu" signal "IN1")
		(8 "In3.Cu" signal "GND1")
		(10 "In4.Cu" signal "IN2")
		(12 "In5.Cu" signal "GND2")
		(14 "In6.Cu" signal "IN3")
		(16 "In7.Cu" signal "GND3")
		(18 "In8.Cu" signal "VCC")
		(20 "In9.Cu" signal "VCC1")
		(22 "In10.Cu" signal "GND4")
		(24 "In11.Cu" signal "IN4")
		(26 "In12.Cu" signal "GND5")
		(28 "In13.Cu" signal "IN5")
		(30 "In14.Cu" signal "GND6")
		(32 "In15.Cu" signal "IN6")
		(34 "In16.Cu" signal "GND7")
		(2 "B.Cu" signal "BOTTOM")
		(9 "F.Adhes" user "F.Adhesive")
		(11 "B.Adhes" user "B.Adhesive")
		(13 "F.Paste" user "Package Geometry/Pastemask Top")
		(15 "B.Paste" user "Package Geometry/Pastemask Bottom")
		(5 "F.SilkS" user "Ref Des/Silkscreen Top")
		(7 "B.SilkS" user "Ref Des/Silkscreen Bottom")
		(1 "F.Mask" user "Board Geometry/Soldermask Top")
		(3 "B.Mask" user "Board Geometry/Soldermask Bottom")
		(17 "Dwgs.User" user "User.Drawings")
		(19 "Cmts.User" user "User.Comments")
		(21 "Eco1.User" user "User.Eco1")
		(23 "Eco2.User" user "User.Eco2")
		(25 "Edge.Cuts" user "Board Geometry/Outline")
		(27 "Margin" user)
		(31 "F.CrtYd" user "Package Geometry/Place Bound Top")
		(29 "B.CrtYd" user "Package Geometry/Place Bound Bottom")
		(35 "F.Fab" user "Ref Des/Assembly Top")
		(33 "B.Fab" user "Ref Des/Assembly Bottom")
	)
	(footprint ""
		(layer "B.Cu")
		(at 313.014614 -258.379976 -90)
		(property "Reference" "C526"
			(at 0 0 90)
			(layer "B.SilkS")
			(hide yes)
			(effects
				(font
					(size 1.27 1.27)
				)
				(justify mirror)
			)
		)
		(property "Value" ""
			(at 0 0 90)
			(layer "B.Fab")
			(effects
				(font
					(size 1.27 1.27)
				)
				(justify mirror)
			)
		)
		(duplicate_pad_numbers_are_jumpers no)
		(fp_line
			(start -1.524 0.762)
			(end 1.524 0.762)
			(stroke
				(width 0.1524)
				(type default)
			)
			(layer "B.SilkS")
		)
		(fp_line
			(start 1.524 0.762)
			(end 1.524 -0.762)
			(stroke
				(width 0.1524)
				(type default)
			)
			(layer "B.SilkS")
		)
		(fp_line
			(start -1.524 -0.762)
			(end -1.524 0.762)
			(stroke
				(width 0.1524)
				(type default)
			)
			(layer "B.SilkS")
		)
		(fp_line
			(start 1.524 -0.762)
			(end -1.524 -0.762)
			(stroke
				(width 0.1524)
				(type default)
			)
			(layer "B.SilkS")
		)
		(fp_line
			(start -1.1049 0.724916)
			(end -1.1049 -0.724916)
			(stroke
				(width 0.1)
				(type default)
			)
			(layer "B.Fab")
		)
		(fp_line
			(start 1.1049 0.724916)
			(end -1.1049 0.724916)
			(stroke
				(width 0.1)
				(type default)
			)
			(layer "B.Fab")
		)
		(fp_line
			(start -1.1049 -0.724916)
			(end 1.1049 -0.724916)
			(stroke
				(width 0.1)
				(type default)
			)
			(layer "B.Fab")
		)
		(fp_line
			(start 1.1049 -0.724916)
			(end 1.1049 0.724916)
			(stroke
				(width 0.1)
				(type default)
			)
			(layer "B.Fab")
		)
		(pad "1" smd rect
			(at 0.889 0 270)
			(size 1.016 1.27)
			(layers "B.Cu" "B.Mask" "B.Paste")
			(net "PVCCFA_EHV_FIVRA_CPU0")
		)
		(pad "2" smd rect
			(at -0.889 0 270)
			(size 1.016 1.27)
			(layers "B.Cu" "B.Mask" "B.Paste")
			(net "GND")
		)
	)
	(footprint ""
		(layer "B.Cu")
		(at 105.679494 -252.17628 -90)
		(property "Reference" "C330"
			(at 0 0 90)
			(layer "B.SilkS")
			(hide yes)
			(effects
				(font
					(size 1.27 1.27)
				)
				(justify mirror)
			)
		)
		(property "Value" ""
			(at 0 0 90)
			(layer "B.Fab")
			(effects
				(font
					(size 1.27 1.27)
				)
				(justify mirror)
			)
		)
		(duplicate_pad_numbers_are_jumpers no)
		(fp_line
			(start -1.524 0.762)
			(end 1.524 0.762)
			(stroke
				(width 0.1524)
				(type default)
			)
			(layer "B.SilkS")
		)
		(fp_line
			(start 1.524 0.762)
			(end 1.524 -0.762)
			(stroke
				(width 0.1524)
				(type default)
			)
			(layer "B.SilkS")
		)
		(fp_line
			(start -1.524 -0.762)
			(end -1.524 0.762)
			(stroke
				(width 0.1524)
				(type default)
			)
			(layer "B.SilkS")
		)
		(fp_line
			(start 1.524 -0.762)
			(end -1.524 -0.762)
			(stroke
				(width 0.1524)
				(type default)
			)
			(layer "B.SilkS")
		)
		(fp_line
			(start -1.1049 0.724916)
			(end -1.1049 -0.724916)
			(stroke
				(width 0.1)
				(type default)
			)
			(layer "B.Fab")
		)
		(fp_line
			(start 1.1049 0.724916)
			(end -1.1049 0.724916)
			(stroke
				(width 0.1)
				(type default)
			)
			(layer "B.Fab")
		)
		(fp_line
			(start -1.1049 -0.724916)
			(end 1.1049 -0.724916)
			(stroke
				(width 0.1)
				(type default)
			)
			(layer "B.Fab")
		)
		(fp_line
			(start 1.1049 -0.724916)
			(end 1.1049 0.724916)
			(stroke
				(width 0.1)
				(type default)
			)
			(layer "B.Fab")
		)
		(pad "1" smd rect
			(at 0.889 0 270)
			(size 1.016 1.27)
			(layers "B.Cu" "B.Mask" "B.Paste")
			(net "PVCCIN_CPU1")
		)
		(pad "2" smd rect
			(at -0.889 0 270)
			(size 1.016 1.27)
			(layers "B.Cu" "B.Mask" "B.Paste")
			(net "GND")
		)
	)
	(footprint ""
		(layer "B.Cu")
		(at 105.679494 -259.53212 90)
		(property "Reference" "C461"
			(at 0 0 90)
			(layer "B.SilkS")
			(hide yes)
			(effects
				(font
					(size 1.27 1.27)
				)
				(justify mirror)
			)
		)
		(property "Value" ""
			(at 0 0 90)
			(layer "B.Fab")
			(effects
				(font
					(size 1.27 1.27)
				)
				(justify mirror)
			)
		)
		(duplicate_pad_numbers_are_jumpers no)
		(fp_line
			(start 1.524 -0.762)
			(end -1.524 -0.762)
			(stroke
				(width 0.1524)
				(type default)
			)
			(layer "B.SilkS")
		)
		(fp_line
			(start -1.524 -0.762)
			(end -1.524 0.762)
			(stroke
				(width 0.1524)
				(type default)
			)
			(layer "B.SilkS")
		)
		(fp_line
			(start 1.524 0.762)
			(end 1.524 -0.762)
			(stroke
				(width 0.1524)
				(type default)
			)
			(layer "B.SilkS")
		)
		(fp_line
			(start -1.524 0.762)
			(end 1.524 0.762)
			(stroke
				(width 0.1524)
				(type default)
			)
			(layer "B.SilkS")
		)
		(fp_line
			(start 1.1049 -0.724916)
			(end 1.1049 0.724916)
			(stroke
				(width 0.1)
				(type default)
			)
			(layer "B.Fab")
		)
		(fp_line
			(start -1.1049 -0.724916)
			(end 1.1049 -0.724916)
			(stroke
				(width 0.1)
				(type default)
			)
			(layer "B.Fab")
		)
		(fp_line
			(start 1.1049 0.724916)
			(end -1.1049 0.724916)
			(stroke
				(width 0.1)
				(type default)
			)
			(layer "B.Fab")
		)
		(fp_line
			(start -1.1049 0.724916)
			(end -1.1049 -0.724916)
			(stroke
				(width 0.1)
				(type default)
			)
			(layer "B.Fab")
		)
		(pad "1" smd rect
			(at 0.889 0 90)
			(size 1.016 1.27)
			(layers "B.Cu" "B.Mask" "B.Paste")
			(net "PVCCFA_EHV_FIVRA_CPU1")
		)
		(pad "2" smd rect
			(at -0.889 0 90)
			(size 1.016 1.27)
			(layers "B.Cu" "B.Mask" "B.Paste")
			(net "GND")
		)
	)
)
